# BASEBOARD_FAB2 (Tioga Pass) — schematic netlist excerpt (pin names and nets, part order shuffled) for the footprints in the layout excerpt that follows; sources: Cadence DE-HDL packaged netlist, KiCad conversion of Wiwynn_Tioga_Pass_MB.brd

EU4G1  NCP3232L  IC  pkg SM  page 233
  SS  = VR_PVPP_GHJ_SS
  FB  = VR_FB_PVPP_GHJ
  COMP  = VR_COMP_PVPP_GHJ_3
  ISET  = VR_PVPP_GHJ_ISET
  AGND  = AGND_PVPP_GHJ
  OTS  = AGND_PVPP_GHJ
  PG  = PWRGD_PVPP_GHJ_R
  VIN(0)  = VR_FET_SW_P12V_STBY_PVPP_GHJ
  VIN(1)  = VR_FET_SW_P12V_STBY_PVPP_GHJ
  VIN(2)  = VR_FET_SW_P12V_STBY_PVPP_GHJ
  VIN(3)  = VR_FET_SW_P12V_STBY_PVPP_GHJ
  VIN(4)  = VR_FET_SW_P12V_STBY_PVPP_GHJ
  VIN(5)  = VR_FET_SW_P12V_STBY_PVPP_GHJ
  VIN(6)  = VR_FET_SW_P12V_STBY_PVPP_GHJ
  VSWH(0)  = VR_PVPP_GHJ_PHASE
  PGND(0)  = GND
  PGND(1)  = GND
  PGND(2)  = GND
  PGND(3)  = GND
  PGND(4)  = GND
  PGND(5)  = GND
  PGND(6)  = GND
  PGND(7)  = GND
  PGND(8)  = GND
  PGND(9)  = GND
  PGND(10)  = GND
  PGND(11)  = GND
  PGND(12)  = GND
  VSWH(1)  = VR_PVPP_GHJ_PHASE
  VSWH(2)  = VR_PVPP_GHJ_PHASE
  VSWH(3)  = VR_PVPP_GHJ_PHASE
  VSWH(4)  = VR_PVPP_GHJ_PHASE
  VSWH(5)  = VR_PVPP_GHJ_PHASE
  VSWH(6)  = VR_PVPP_GHJ_PHASE
  VSW  = VR_PVPP_GHJ_PHASE
  BST  = VR_PVPP_GHJ_BOOT
  PGND(13)  = GND
  VB  = VR_VB_PVPP_GHJ
  VCC  = VR_FET_SW_P12V_STBY_PVPP_GHJ
  EN  = FM_PVPP_PVDDQ_CPU1_EN_GHJ
  GND  = GND
  VIN(7)  = VR_FET_SW_P12V_STBY_PVPP_GHJ
  VSWH(7)  = VR_PVPP_GHJ_PHASE

(kicad_pcb
	(version 20260206)
	(generator "pcbnew")
	(generator_version "10.0")
	(general
		(thickness 1.6)
		(legacy_teardrops no)
	)
	(paper "A4")
	(title_block
		(title "Wiwynn_Tioga_Pass_MB.brd")
		(comment 1 "Tioga Pass / footprint 1232 of 4770 (EU4G1), pads 1-17 of 43")
	)
	(layers
		(0 "F.Cu" signal "TOP")
		(4 "In1.Cu" signal "L2GND")
		(6 "In2.Cu" signal "L3")
		(8 "In3.Cu" signal "L4GND")
		(10 "In4.Cu" signal "L5")
		(12 "In5.Cu" signal "L6GND")
		(14 "In6.Cu" signal "L7VCC")
		(16 "In7.Cu" signal "L8VCC")
		(18 "In8.Cu" signal "L9GND")
		(20 "In9.Cu" signal "L10")
		(22 "In10.Cu" signal "L11GND")
		(24 "In11.Cu" signal "L12")
		(26 "In12.Cu" signal "L13GND")
		(2 "B.Cu" signal "BOTTOM")
		(9 "F.Adhes" user "F.Adhesive")
		(11 "B.Adhes" user "B.Adhesive")
		(13 "F.Paste" user "Package Geometry/Pastemask Top")
		(15 "B.Paste" user "Package Geometry/Pastemask Bottom")
		(5 "F.SilkS" user "Ref Des/Silkscreen Top")
		(7 "B.SilkS" user "Ref Des/Silkscreen Bottom")
		(1 "F.Mask" user "Board Geometry/Soldermask Top")
		(3 "B.Mask" user "Board Geometry/Soldermask Bottom")
		(17 "Dwgs.User" user "User.Drawings")
		(19 "Cmts.User" user "User.Comments")
		(21 "Eco1.User" user "User.Eco1")
		(23 "Eco2.User" user "User.Eco2")
		(25 "Edge.Cuts" user "Board Geometry/Outline")
		(27 "Margin" user)
		(31 "F.CrtYd" user "Package Geometry/Place Bound Top")
		(29 "B.CrtYd" user "Package Geometry/Place Bound Bottom")
		(35 "F.Fab" user "Ref Des/Assembly Top")
		(33 "B.Fab" user "Ref Des/Assembly Bottom")
	)
	(footprint ""
		(layer "F.Cu")
		(at 177.673 -13.335 90)
		(property "Reference" "EU4G1"
			(at 5.18033 -0.889 0)
			(unlocked yes)
			(layer "F.SilkS")
			(effects
				(font
					(size 0.7874 0.5842)
					(thickness 0.1524)
				)
				(justify left)
			)
		)
		(property "Value" ""
			(at 0 0 90)
			(layer "F.Fab")
			(effects
				(font
					(size 1.27 1.27)
				)
			)
		)
		(duplicate_pad_numbers_are_jumpers no)
		(pad "1" smd custom
			(at -2.8321 -2.249932 90)
			(size 0.06985 0.06985)
			(layers "F.Cu" "F.Mask" "F.Paste")
			(net "VR_PVPP_GHJ_SS")
			(options
				(clearance outline)
				(anchor circle)
			)
			(primitives
				(gr_poly
					(pts
						(arc
							(start 0.2413 -0.1397)
							(mid 0.381 0)
							(end 0.2413 0.1397)
						)
						(xy -0.381 0.1397) (xy -0.381 -0.1397)
					)
					(width 0)
					(fill yes)
				)
			)
		)
		(pad "2" smd custom
			(at -2.8321 -1.75006 90)
			(size 0.06985 0.06985)
			(layers "F.Cu" "F.Mask" "F.Paste")
			(net "VR_FB_PVPP_GHJ")
			(options
				(clearance outline)
				(anchor circle)
			)
			(primitives
				(gr_poly
					(pts
						(arc
							(start 0.2413 -0.1397)
							(mid 0.381 0)
							(end 0.2413 0.1397)
						)
						(xy -0.381 0.1397) (xy -0.381 -0.1397)
					)
					(width 0)
					(fill yes)
				)
			)
		)
		(pad "3" smd custom
			(at -2.8321 -1.249934 90)
			(size 0.06985 0.06985)
			(layers "F.Cu" "F.Mask" "F.Paste")
			(net "VR_COMP_PVPP_GHJ_3")
			(options
				(clearance outline)
				(anchor circle)
			)
			(primitives
				(gr_poly
					(pts
						(arc
							(start 0.2413 -0.1397)
							(mid 0.381 0)
							(end 0.2413 0.1397)
						)
						(xy -0.381 0.1397) (xy -0.381 -0.1397)
					)
					(width 0)
					(fill yes)
				)
			)
		)
		(pad "4" smd custom
			(at -2.8321 -0.750062 90)
			(size 0.06985 0.06985)
			(layers "F.Cu" "F.Mask" "F.Paste")
			(net "VR_PVPP_GHJ_ISET")
			(options
				(clearance outline)
				(anchor circle)
			)
			(primitives
				(gr_poly
					(pts
						(arc
							(start 0.2413 -0.1397)
							(mid 0.381 0)
							(end 0.2413 0.1397)
						)
						(xy -0.381 0.1397) (xy -0.381 -0.1397)
					)
					(width 0)
					(fill yes)
				)
			)
		)
		(pad "5" smd custom
			(at -2.8321 -0.249936 90)
			(size 0.06985 0.06985)
			(layers "F.Cu" "F.Mask" "F.Paste")
			(net "AGND_PVPP_GHJ")
			(options
				(clearance outline)
				(anchor circle)
			)
			(primitives
				(gr_poly
					(pts
						(arc
							(start 0.2413 -0.1397)
							(mid 0.381 0)
							(end 0.2413 0.1397)
						)
						(xy -0.381 0.1397) (xy -0.381 -0.1397)
					)
					(width 0)
					(fill yes)
				)
			)
		)
		(pad "6" smd custom
			(at -2.8321 0.249936 90)
			(size 0.06985 0.06985)
			(layers "F.Cu" "F.Mask" "F.Paste")
			(net "AGND_PVPP_GHJ")
			(options
				(clearance outline)
				(anchor circle)
			)
			(primitives
				(gr_poly
					(pts
						(arc
							(start 0.2413 -0.1397)
							(mid 0.381 0)
							(end 0.2413 0.1397)
						)
						(xy -0.381 0.1397) (xy -0.381 -0.1397)
					)
					(width 0)
					(fill yes)
				)
			)
		)
		(pad "7" smd custom
			(at -2.8321 0.750062 90)
			(size 0.06985 0.06985)
			(layers "F.Cu" "F.Mask" "F.Paste")
			(net "PWRGD_PVPP_GHJ_R")
			(options
				(clearance outline)
				(anchor circle)
			)
			(primitives
				(gr_poly
					(pts
						(arc
							(start 0.2413 -0.1397)
							(mid 0.381 0)
							(end 0.2413 0.1397)
						)
						(xy -0.381 0.1397) (xy -0.381 -0.1397)
					)
					(width 0)
					(fill yes)
				)
			)
		)
		(pad "8" smd custom
			(at -2.8321 1.249934 90)
			(size 0.06985 0.06985)
			(layers "F.Cu" "F.Mask" "F.Paste")
			(net "VR_FET_SW_P12V_STBY_PVPP_GHJ")
			(options
				(clearance outline)
				(anchor circle)
			)
			(primitives
				(gr_poly
					(pts
						(arc
							(start 0.2413 -0.1397)
							(mid 0.381 0)
							(end 0.2413 0.1397)
						)
						(xy -0.381 0.1397) (xy -0.381 -0.1397)
					)
					(width 0)
					(fill yes)
				)
			)
		)
		(pad "9" smd custom
			(at -2.8321 1.75006 90)
			(size 0.06985 0.06985)
			(layers "F.Cu" "F.Mask" "F.Paste")
			(net "VR_FET_SW_P12V_STBY_PVPP_GHJ")
			(options
				(clearance outline)
				(anchor circle)
			)
			(primitives
				(gr_poly
					(pts
						(arc
							(start 0.2413 -0.1397)
							(mid 0.381 0)
							(end 0.2413 0.1397)
						)
						(xy -0.381 0.1397) (xy -0.381 -0.1397)
					)
					(width 0)
					(fill yes)
				)
			)
		)
		(pad "10" smd custom
			(at -2.8321 2.249932 90)
			(size 0.06985 0.06985)
			(layers "F.Cu" "F.Mask" "F.Paste")
			(net "VR_FET_SW_P12V_STBY_PVPP_GHJ")
			(options
				(clearance outline)
				(anchor circle)
			)
			(primitives
				(gr_poly
					(pts
						(arc
							(start 0.2413 -0.1397)
							(mid 0.381 0)
							(end 0.2413 0.1397)
						)
						(xy -0.381 0.1397) (xy -0.381 -0.1397)
					)
					(width 0)
					(fill yes)
				)
			)
		)
		(pad "11" smd custom
			(at -2.249932 2.8321 90)
			(size 0.06985 0.06985)
			(layers "F.Cu" "F.Mask" "F.Paste")
			(net "VR_FET_SW_P12V_STBY_PVPP_GHJ")
			(options
				(clearance outline)
				(anchor circle)
			)
			(primitives
				(gr_poly
					(pts
						(arc
							(start -0.1397 -0.2413)
							(mid 0 -0.381)
							(end 0.1397 -0.2413)
						)
						(xy 0.1397 0.381) (xy -0.1397 0.381)
					)
					(width 0)
					(fill yes)
				)
			)
		)
		(pad "12" smd custom
			(at -1.75006 2.8321 90)
			(size 0.06985 0.06985)
			(layers "F.Cu" "F.Mask" "F.Paste")
			(net "VR_FET_SW_P12V_STBY_PVPP_GHJ")
			(options
				(clearance outline)
				(anchor circle)
			)
			(primitives
				(gr_poly
					(pts
						(arc
							(start -0.1397 -0.2413)
							(mid 0 -0.381)
							(end 0.1397 -0.2413)
						)
						(xy 0.1397 0.381) (xy -0.1397 0.381)
					)
					(width 0)
					(fill yes)
				)
			)
		)
		(pad "13" smd custom
			(at -1.249934 2.8321 90)
			(size 0.06985 0.06985)
			(layers "F.Cu" "F.Mask" "F.Paste")
			(net "VR_FET_SW_P12V_STBY_PVPP_GHJ")
			(options
				(clearance outline)
				(anchor circle)
			)
			(primitives
				(gr_poly
					(pts
						(arc
							(start -0.1397 -0.2413)
							(mid 0 -0.381)
							(end 0.1397 -0.2413)
						)
						(xy 0.1397 0.381) (xy -0.1397 0.381)
					)
					(width 0)
					(fill yes)
				)
			)
		)
		(pad "14" smd custom
			(at -0.750062 2.8321 90)
			(size 0.06985 0.06985)
			(layers "F.Cu" "F.Mask" "F.Paste")
			(net "VR_FET_SW_P12V_STBY_PVPP_GHJ")
			(options
				(clearance outline)
				(anchor circle)
			)
			(primitives
				(gr_poly
					(pts
						(arc
							(start -0.1397 -0.2413)
							(mid 0 -0.381)
							(end 0.1397 -0.2413)
						)
						(xy 0.1397 0.381) (xy -0.1397 0.381)
					)
					(width 0)
					(fill yes)
				)
			)
		)
		(pad "15" smd custom
			(at -0.249936 2.8321 90)
			(size 0.06985 0.06985)
			(layers "F.Cu" "F.Mask" "F.Paste")
			(net "VR_PVPP_GHJ_PHASE")
			(options
				(clearance outline)
				(anchor circle)
			)
			(primitives
				(gr_poly
					(pts
						(arc
							(start -0.1397 -0.2413)
							(mid 0 -0.381)
							(end 0.1397 -0.2413)
						)
						(xy 0.1397 0.381) (xy -0.1397 0.381)
					)
					(width 0)
					(fill yes)
				)
			)
		)
		(pad "16" smd custom
			(at 0.249936 2.8321 90)
			(size 0.06985 0.06985)
			(layers "F.Cu" "F.Mask" "F.Paste")
			(net "GND")
			(options
				(clearance outline)
				(anchor circle)
			)
			(primitives
				(gr_poly
					(pts
						(arc
							(start -0.1397 -0.2413)
							(mid 0 -0.381)
							(end 0.1397 -0.2413)
						)
						(xy 0.1397 0.381) (xy -0.1397 0.381)
					)
					(width 0)
					(fill yes)
				)
			)
		)
		(pad "17" smd custom
			(at 0.750062 2.8321 90)
			(size 0.06985 0.06985)
			(layers "F.Cu" "F.Mask" "F.Paste")
			(net "GND")
			(options
				(clearance outline)
				(anchor circle)
			)
			(primitives
				(gr_poly
					(pts
						(arc
							(start -0.1397 -0.2413)
							(mid 0 -0.381)
							(end 0.1397 -0.2413)
						)
						(xy 0.1397 0.381) (xy -0.1397 0.381)
					)
					(width 0)
					(fill yes)
				)
			)
		)
	)
)
